# S9S_MB_2U (Grand Teton) — schematic netlist excerpt (pin names and nets, part order shuffled) for the footprints in the layout excerpt that follows; sources: Cadence DE-HDL packaged netlist, KiCad conversion of 03242023_DA0F0TMBIJ0_F0T_Motherboard_J_brd_V01_OCP.brd

R852  Q_RES  0 5% CHIP  pkg 0402LF  page 128 : A = RST_CPU0_DRAM_CD_N ; B = RST_CPU0_DRAM_CD_PLD_N
R3353  Q_RES  0 5% CHIP  pkg 0402LF  page 207 : A = CLK_100M_GPU_1_R_DN ; B = CLK_100M_GPU_1_DN
C1522  Q_CAP_DIFFBUS  DIFF BUS_0.22UF 6.3V 20% X6S  pkg C0201  page 177 : \1\ = P5E_CPU1_PE3_TX_C_DN<12> ; \2\ = P5E_CPU1_PE3_TX_DN<12>

(kicad_pcb
	(version 20260206)
	(generator "pcbnew")
	(generator_version "10.0")
	(general
		(thickness 1.6)
		(legacy_teardrops no)
	)
	(paper "A4")
	(title_block
		(title "03242023_DA0F0TMBIJ0_F0T_Motherboard_J_brd_V01_OCP.brd")
		(comment 1 "Grand Teton / footprints 3984-3986 of 6105")
	)
	(layers
		(0 "F.Cu" signal "TOP")
		(4 "In1.Cu" signal "GND")
		(6 "In2.Cu" signal "IN1")
		(8 "In3.Cu" signal "GND1")
		(10 "In4.Cu" signal "IN2")
		(12 "In5.Cu" signal "GND2")
		(14 "In6.Cu" signal "IN3")
		(16 "In7.Cu" signal "GND3")
		(18 "In8.Cu" signal "VCC")
		(20 "In9.Cu" signal "VCC1")
		(22 "In10.Cu" signal "GND4")
		(24 "In11.Cu" signal "IN4")
		(26 "In12.Cu" signal "GND5")
		(28 "In13.Cu" signal "IN5")
		(30 "In14.Cu" signal "GND6")
		(32 "In15.Cu" signal "IN6")
		(34 "In16.Cu" signal "GND7")
		(2 "B.Cu" signal "BOTTOM")
		(9 "F.Adhes" user "F.Adhesive")
		(11 "B.Adhes" user "B.Adhesive")
		(13 "F.Paste" user "Package Geometry/Pastemask Top")
		(15 "B.Paste" user "Package Geometry/Pastemask Bottom")
		(5 "F.SilkS" user "Ref Des/Silkscreen Top")
		(7 "B.SilkS" user "Ref Des/Silkscreen Bottom")
		(1 "F.Mask" user "Board Geometry/Soldermask Top")
		(3 "B.Mask" user "Board Geometry/Soldermask Bottom")
		(17 "Dwgs.User" user "User.Drawings")
		(19 "Cmts.User" user "User.Comments")
		(21 "Eco1.User" user "User.Eco1")
		(23 "Eco2.User" user "User.Eco2")
		(25 "Edge.Cuts" user "Board Geometry/Outline")
		(27 "Margin" user)
		(31 "F.CrtYd" user "Package Geometry/Place Bound Top")
		(29 "B.CrtYd" user "Package Geometry/Place Bound Bottom")
		(35 "F.Fab" user "Ref Des/Assembly Top")
		(33 "B.Fab" user "Ref Des/Assembly Bottom")
	)
	(footprint ""
		(layer "F.Cu")
		(at 106.70921 -414.741868 180)
		(property "Reference" "R3353"
			(at 0 0 180)
			(layer "F.SilkS")
			(hide yes)
			(effects
				(font
					(size 1.27 1.27)
				)
			)
		)
		(property "Value" ""
			(at 0 0 180)
			(layer "F.Fab")
			(effects
				(font
					(size 1.27 1.27)
				)
			)
		)
		(duplicate_pad_numbers_are_jumpers no)
		(fp_line
			(start 0.7874 -0.4064)
			(end 0.7874 0.09144)
			(stroke
				(width 0.1524)
				(type default)
			)
			(layer "F.SilkS")
		)
		(fp_line
			(start 0.42799 0.4064)
			(end -0.41275 0.4064)
			(stroke
				(width 0.1524)
				(type default)
			)
			(layer "F.SilkS")
		)
		(fp_line
			(start -0.7874 0.03302)
			(end -0.7874 -0.4064)
			(stroke
				(width 0.1524)
				(type default)
			)
			(layer "F.SilkS")
		)
		(fp_line
			(start -0.7874 -0.4064)
			(end 0.7874 -0.4064)
			(stroke
				(width 0.1524)
				(type default)
			)
			(layer "F.SilkS")
		)
		(fp_line
			(start 0.67945 0.3048)
			(end 0.120396 0.3048)
			(stroke
				(width 0.1)
				(type default)
			)
			(layer "F.Fab")
		)
		(fp_line
			(start 0.67945 -0.3048)
			(end 0.67945 0.3048)
			(stroke
				(width 0.1)
				(type default)
			)
			(layer "F.Fab")
		)
		(fp_line
			(start 0.12065 -0.2794)
			(end 0.12065 -0.3048)
			(stroke
				(width 0.1)
				(type default)
			)
			(layer "F.Fab")
		)
		(fp_line
			(start 0.12065 -0.3048)
			(end 0.67945 -0.3048)
			(stroke
				(width 0.1)
				(type default)
			)
			(layer "F.Fab")
		)
		(fp_line
			(start 0.120396 0.3048)
			(end 0.120396 0.2794)
			(stroke
				(width 0.1)
				(type default)
			)
			(layer "F.Fab")
		)
		(fp_line
			(start 0.120396 0.2794)
			(end -0.12065 0.2794)
			(stroke
				(width 0.1)
				(type default)
			)
			(layer "F.Fab")
		)
		(fp_line
			(start -0.12065 0.3048)
			(end -0.67945 0.3048)
			(stroke
				(width 0.1)
				(type default)
			)
			(layer "F.Fab")
		)
		(fp_line
			(start -0.12065 0.2794)
			(end -0.12065 0.3048)
			(stroke
				(width 0.1)
				(type default)
			)
			(layer "F.Fab")
		)
		(fp_line
			(start -0.12065 -0.2794)
			(end 0.12065 -0.2794)
			(stroke
				(width 0.1)
				(type default)
			)
			(layer "F.Fab")
		)
		(fp_line
			(start -0.12065 -0.305054)
			(end -0.12065 -0.2794)
			(stroke
				(width 0.1)
				(type default)
			)
			(layer "F.Fab")
		)
		(fp_line
			(start -0.67945 0.3048)
			(end -0.67945 -0.305054)
			(stroke
				(width 0.1)
				(type default)
			)
			(layer "F.Fab")
		)
		(fp_line
			(start -0.67945 -0.305054)
			(end -0.12065 -0.305054)
			(stroke
				(width 0.1)
				(type default)
			)
			(layer "F.Fab")
		)
		(pad "1" smd circle
			(at -0.40005 0 180)
			(size 0 0)
			(layers "F.Cu" "F.Mask" "F.Paste")
			(net "CLK_100M_GPU_1_R_DN")
		)
		(pad "2" smd circle
			(at 0.40005 0 180)
			(size 0 0)
			(layers "F.Cu" "F.Mask" "F.Paste")
			(net "CLK_100M_GPU_1_DN")
		)
	)
	(footprint ""
		(layer "F.Cu")
		(at 130.665474 -408.517344 -90)
		(property "Reference" "C1522"
			(at 0 0 270)
			(layer "F.SilkS")
			(hide yes)
			(effects
				(font
					(size 1.27 1.27)
				)
			)
		)
		(property "Value" ""
			(at 0 0 270)
			(layer "F.Fab")
			(effects
				(font
					(size 1.27 1.27)
				)
			)
		)
		(duplicate_pad_numbers_are_jumpers no)
		(fp_line
			(start -0.299974 0.150114)
			(end -0.299974 -0.150114)
			(stroke
				(width 0.1)
				(type default)
			)
			(layer "F.Fab")
		)
		(fp_line
			(start 0.299974 0.150114)
			(end -0.299974 0.150114)
			(stroke
				(width 0.1)
				(type default)
			)
			(layer "F.Fab")
		)
		(fp_line
			(start -0.299974 -0.150114)
			(end 0.299974 -0.150114)
			(stroke
				(width 0.1)
				(type default)
			)
			(layer "F.Fab")
		)
		(fp_line
			(start 0.299974 -0.150114)
			(end 0.299974 0.150114)
			(stroke
				(width 0.1)
				(type default)
			)
			(layer "F.Fab")
		)
		(pad "1" smd rect
			(at -0.2667 0 270)
			(size 0.3048 0.381)
			(layers "F.Cu" "F.Mask" "F.Paste")
			(net "P5E_CPU1_PE3_TX_C_DN<12>")
		)
		(pad "2" smd rect
			(at 0.2667 0 270)
			(size 0.3048 0.381)
			(layers "F.Cu" "F.Mask" "F.Paste")
			(net "P5E_CPU1_PE3_TX_DN<12>")
		)
	)
	(footprint ""
		(layer "F.Cu")
		(at 112.40008 -119.846598 -90)
		(property "Reference" "R852"
			(at 0 0 270)
			(layer "F.SilkS")
			(hide yes)
			(effects
				(font
					(size 1.27 1.27)
				)
			)
		)
		(property "Value" ""
			(at 0 0 270)
			(layer "F.Fab")
			(effects
				(font
					(size 1.27 1.27)
				)
			)
		)
		(duplicate_pad_numbers_are_jumpers no)
		(fp_line
			(start -0.7874 0.4064)
			(end -0.7874 -0.4064)
			(stroke
				(width 0.1524)
				(type default)
			)
			(layer "F.SilkS")
		)
		(fp_line
			(start 0.7874 0.4064)
			(end -0.7874 0.4064)
			(stroke
				(width 0.1524)
				(type default)
			)
			(layer "F.SilkS")
		)
		(fp_line
			(start -0.7874 -0.4064)
			(end 0.7874 -0.4064)
			(stroke
				(width 0.1524)
				(type default)
			)
			(layer "F.SilkS")
		)
		(fp_line
			(start 0.7874 -0.4064)
			(end 0.7874 0.4064)
			(stroke
				(width 0.1524)
				(type default)
			)
			(layer "F.SilkS")
		)
		(fp_line
			(start -0.67945 0.3048)
			(end -0.67945 -0.305054)
			(stroke
				(width 0.1)
				(type default)
			)
			(layer "F.Fab")
		)
		(fp_line
			(start -0.12065 0.3048)
			(end -0.67945 0.3048)
			(stroke
				(width 0.1)
				(type default)
			)
			(layer "F.Fab")
		)
		(fp_line
			(start 0.120396 0.3048)
			(end 0.120396 0.2794)
			(stroke
				(width 0.1)
				(type default)
			)
			(layer "F.Fab")
		)
		(fp_line
			(start 0.67945 0.3048)
			(end 0.120396 0.3048)
			(stroke
				(width 0.1)
				(type default)
			)
			(layer "F.Fab")
		)
		(fp_line
			(start -0.12065 0.2794)
			(end -0.12065 0.3048)
			(stroke
				(width 0.1)
				(type default)
			)
			(layer "F.Fab")
		)
		(fp_line
			(start 0.120396 0.2794)
			(end -0.12065 0.2794)
			(stroke
				(width 0.1)
				(type default)
			)
			(layer "F.Fab")
		)
		(fp_line
			(start -0.12065 -0.2794)
			(end 0.12065 -0.2794)
			(stroke
				(width 0.1)
				(type default)
			)
			(layer "F.Fab")
		)
		(fp_line
			(start 0.12065 -0.2794)
			(end 0.12065 -0.3048)
			(stroke
				(width 0.1)
				(type default)
			)
			(layer "F.Fab")
		)
		(fp_line
			(start 0.12065 -0.3048)
			(end 0.67945 -0.3048)
			(stroke
				(width 0.1)
				(type default)
			)
			(layer "F.Fab")
		)
		(fp_line
			(start 0.67945 -0.3048)
			(end 0.67945 0.3048)
			(stroke
				(width 0.1)
				(type default)
			)
			(layer "F.Fab")
		)
		(fp_line
			(start -0.67945 -0.305054)
			(end -0.12065 -0.305054)
			(stroke
				(width 0.1)
				(type default)
			)
			(layer "F.Fab")
		)
		(fp_line
			(start -0.12065 -0.305054)
			(end -0.12065 -0.2794)
			(stroke
				(width 0.1)
				(type default)
			)
			(layer "F.Fab")
		)
		(pad "1" smd circle
			(at -0.40005 0 270)
			(size 0 0)
			(layers "F.Cu" "F.Mask" "F.Paste")
			(net "RST_CPU0_DRAM_CD_N")
		)
		(pad "2" smd circle
			(at 0.40005 0 270)
			(size 0 0)
			(layers "F.Cu" "F.Mask" "F.Paste")
			(net "RST_CPU0_DRAM_CD_PLD_N")
		)
	)
)
